# T6G (Grand Teton) — schematic netlist excerpt (pin names and nets, part order shuffled) for the footprints in the layout excerpt that follows; sources: Cadence DE-HDL packaged netlist, KiCad conversion of 04192023_DAF0TMB3IC0_F0TG_MB_C_brd_V02_OCP.brd

R230  Q_RES  0 5% CHIP  pkg 0402LF  page 81 : A = PWRGD_PVDDIO_P0 ; B = FM_PWRGD_PVDDIO_P0
PC250  Q_CAP  470PF 50V 10% X7R  pkg 0402  page 210 : A = PVDDCR_CPU0_P1_TEMP0 ; B = GND
PC328_2  Q_CAP  22UF 16V 20% X6S  pkg C0805  page 215 : A = SW_P12V_AUX_PVDDCR_SOC_P1_FLT ; B = GND

(kicad_pcb
	(version 20260206)
	(generator "pcbnew")
	(generator_version "10.0")
	(general
		(thickness 1.6)
		(legacy_teardrops no)
	)
	(paper "A4")
	(title_block
		(title "04192023_DAF0TMB3IC0_F0TG_MB_C_brd_V02_OCP.brd")
		(comment 1 "Grand Teton / footprints 8329-8331 of 8354")
	)
	(layers
		(0 "F.Cu" signal "TOP")
		(4 "In1.Cu" signal "GND")
		(6 "In2.Cu" signal "IN1")
		(8 "In3.Cu" signal "GND1")
		(10 "In4.Cu" signal "IN2")
		(12 "In5.Cu" signal "GND2")
		(14 "In6.Cu" signal "IN3")
		(16 "In7.Cu" signal "GND3")
		(18 "In8.Cu" signal "VCC")
		(20 "In9.Cu" signal "VCC1")
		(22 "In10.Cu" signal "GND4")
		(24 "In11.Cu" signal "IN4")
		(26 "In12.Cu" signal "GND5")
		(28 "In13.Cu" signal "IN5")
		(30 "In14.Cu" signal "GND6")
		(32 "In15.Cu" signal "IN6")
		(34 "In16.Cu" signal "GND7")
		(2 "B.Cu" signal "BOTTOM")
		(9 "F.Adhes" user "F.Adhesive")
		(11 "B.Adhes" user "B.Adhesive")
		(13 "F.Paste" user "Package Geometry/Pastemask Top")
		(15 "B.Paste" user "Package Geometry/Pastemask Bottom")
		(5 "F.SilkS" user "Ref Des/Silkscreen Top")
		(7 "B.SilkS" user "Ref Des/Silkscreen Bottom")
		(1 "F.Mask" user "Board Geometry/Soldermask Top")
		(3 "B.Mask" user "Board Geometry/Soldermask Bottom")
		(17 "Dwgs.User" user "User.Drawings")
		(19 "Cmts.User" user "User.Comments")
		(21 "Eco1.User" user "User.Eco1")
		(23 "Eco2.User" user "User.Eco2")
		(25 "Edge.Cuts" user "Board Geometry/Outline")
		(27 "Margin" user)
		(31 "F.CrtYd" user "Package Geometry/Place Bound Top")
		(29 "B.CrtYd" user "Package Geometry/Place Bound Bottom")
		(35 "F.Fab" user "Ref Des/Assembly Top")
		(33 "B.Fab" user "Ref Des/Assembly Bottom")
	)
	(footprint ""
		(layer "B.Cu")
		(at 122.745754 -161.411412 90)
		(property "Reference" "PC328_2"
			(at 0 0 90)
			(layer "B.SilkS")
			(hide yes)
			(effects
				(font
					(size 1.27 1.27)
				)
				(justify mirror)
			)
		)
		(property "Value" ""
			(at 0 0 90)
			(layer "B.Fab")
			(effects
				(font
					(size 1.27 1.27)
				)
				(justify mirror)
			)
		)
		(duplicate_pad_numbers_are_jumpers no)
		(fp_line
			(start 1.524 -0.762)
			(end -1.524 -0.762)
			(stroke
				(width 0.1524)
				(type default)
			)
			(layer "B.SilkS")
		)
		(fp_line
			(start -1.524 -0.762)
			(end -1.524 0.762)
			(stroke
				(width 0.1524)
				(type default)
			)
			(layer "B.SilkS")
		)
		(fp_line
			(start 1.524 0.762)
			(end 1.524 -0.762)
			(stroke
				(width 0.1524)
				(type default)
			)
			(layer "B.SilkS")
		)
		(fp_line
			(start -1.524 0.762)
			(end 1.524 0.762)
			(stroke
				(width 0.1524)
				(type default)
			)
			(layer "B.SilkS")
		)
		(fp_line
			(start 1.1049 -0.724916)
			(end 1.1049 0.724916)
			(stroke
				(width 0.1)
				(type default)
			)
			(layer "B.Fab")
		)
		(fp_line
			(start -1.1049 -0.724916)
			(end 1.1049 -0.724916)
			(stroke
				(width 0.1)
				(type default)
			)
			(layer "B.Fab")
		)
		(fp_line
			(start 1.1049 0.724916)
			(end -1.1049 0.724916)
			(stroke
				(width 0.1)
				(type default)
			)
			(layer "B.Fab")
		)
		(fp_line
			(start -1.1049 0.724916)
			(end -1.1049 -0.724916)
			(stroke
				(width 0.1)
				(type default)
			)
			(layer "B.Fab")
		)
		(pad "1" smd rect
			(at 0.889 0 90)
			(size 1.016 1.27)
			(layers "B.Cu" "B.Mask" "B.Paste")
			(net "SW_P12V_AUX_PVDDCR_SOC_P1_FLT")
		)
		(pad "2" smd rect
			(at -0.889 0 90)
			(size 1.016 1.27)
			(layers "B.Cu" "B.Mask" "B.Paste")
			(net "GND")
		)
	)
	(footprint ""
		(layer "B.Cu")
		(at 197.523608 -104.481376)
		(property "Reference" "R230"
			(at 0 0 0)
			(layer "B.SilkS")
			(hide yes)
			(effects
				(font
					(size 1.27 1.27)
				)
				(justify mirror)
			)
		)
		(property "Value" ""
			(at 0 0 0)
			(layer "B.Fab")
			(effects
				(font
					(size 1.27 1.27)
				)
				(justify mirror)
			)
		)
		(duplicate_pad_numbers_are_jumpers no)
		(fp_line
			(start -0.7874 -0.4064)
			(end -0.7874 0.4064)
			(stroke
				(width 0.1524)
				(type default)
			)
			(layer "B.SilkS")
		)
		(fp_line
			(start -0.7874 0.4064)
			(end 0.7874 0.4064)
			(stroke
				(width 0.1524)
				(type default)
			)
			(layer "B.SilkS")
		)
		(fp_line
			(start 0.7874 -0.4064)
			(end -0.7874 -0.4064)
			(stroke
				(width 0.1524)
				(type default)
			)
			(layer "B.SilkS")
		)
		(fp_line
			(start 0.7874 0.4064)
			(end 0.7874 -0.4064)
			(stroke
				(width 0.1524)
				(type default)
			)
			(layer "B.SilkS")
		)
		(fp_line
			(start -0.67945 -0.3048)
			(end -0.67945 0.3048)
			(stroke
				(width 0.1)
				(type default)
			)
			(layer "B.Fab")
		)
		(fp_line
			(start -0.67945 0.3048)
			(end -0.120396 0.3048)
			(stroke
				(width 0.1)
				(type default)
			)
			(layer "B.Fab")
		)
		(fp_line
			(start -0.12065 -0.3048)
			(end -0.67945 -0.3048)
			(stroke
				(width 0.1)
				(type default)
			)
			(layer "B.Fab")
		)
		(fp_line
			(start -0.12065 -0.2794)
			(end -0.12065 -0.3048)
			(stroke
				(width 0.1)
				(type default)
			)
			(layer "B.Fab")
		)
		(fp_line
			(start -0.120396 0.2794)
			(end 0.12065 0.2794)
			(stroke
				(width 0.1)
				(type default)
			)
			(layer "B.Fab")
		)
		(fp_line
			(start -0.120396 0.3048)
			(end -0.120396 0.2794)
			(stroke
				(width 0.1)
				(type default)
			)
			(layer "B.Fab")
		)
		(fp_line
			(start 0.12065 -0.305054)
			(end 0.12065 -0.2794)
			(stroke
				(width 0.1)
				(type default)
			)
			(layer "B.Fab")
		)
		(fp_line
			(start 0.12065 -0.2794)
			(end -0.12065 -0.2794)
			(stroke
				(width 0.1)
				(type default)
			)
			(layer "B.Fab")
		)
		(fp_line
			(start 0.12065 0.2794)
			(end 0.12065 0.3048)
			(stroke
				(width 0.1)
				(type default)
			)
			(layer "B.Fab")
		)
		(fp_line
			(start 0.12065 0.3048)
			(end 0.67945 0.3048)
			(stroke
				(width 0.1)
				(type default)
			)
			(layer "B.Fab")
		)
		(fp_line
			(start 0.67945 -0.305054)
			(end 0.12065 -0.305054)
			(stroke
				(width 0.1)
				(type default)
			)
			(layer "B.Fab")
		)
		(fp_line
			(start 0.67945 0.3048)
			(end 0.67945 -0.305054)
			(stroke
				(width 0.1)
				(type default)
			)
			(layer "B.Fab")
		)
		(pad "1" smd circle
			(at 0.40005 0 180)
			(size 0 0)
			(layers "B.Cu" "B.Mask" "B.Paste")
			(net "PWRGD_PVDDIO_P0")
		)
		(pad "2" smd circle
			(at -0.40005 0 180)
			(size 0 0)
			(layers "B.Cu" "B.Mask" "B.Paste")
			(net "FM_PWRGD_PVDDIO_P0")
		)
	)
	(footprint ""
		(layer "B.Cu")
		(at 101.385878 -143.61541 180)
		(property "Reference" "PC250"
			(at 0 0 0)
			(layer "B.SilkS")
			(hide yes)
			(effects
				(font
					(size 1.27 1.27)
				)
				(justify mirror)
			)
		)
		(property "Value" ""
			(at 0 0 0)
			(layer "B.Fab")
			(effects
				(font
					(size 1.27 1.27)
				)
				(justify mirror)
			)
		)
		(duplicate_pad_numbers_are_jumpers no)
		(fp_line
			(start 0.7874 0.4064)
			(end 0.7874 -0.4064)
			(stroke
				(width 0.1524)
				(type default)
			)
			(layer "B.SilkS")
		)
		(fp_line
			(start 0.7874 -0.4064)
			(end -0.7874 -0.4064)
			(stroke
				(width 0.1524)
				(type default)
			)
			(layer "B.SilkS")
		)
		(fp_line
			(start -0.7874 0.4064)
			(end 0.7874 0.4064)
			(stroke
				(width 0.1524)
				(type default)
			)
			(layer "B.SilkS")
		)
		(fp_line
			(start -0.7874 -0.4064)
			(end -0.7874 0.4064)
			(stroke
				(width 0.1524)
				(type default)
			)
			(layer "B.SilkS")
		)
		(fp_line
			(start 0.67945 0.3048)
			(end 0.67945 -0.305054)
			(stroke
				(width 0.1)
				(type default)
			)
			(layer "B.Fab")
		)
		(fp_line
			(start 0.67945 -0.305054)
			(end 0.12065 -0.305054)
			(stroke
				(width 0.1)
				(type default)
			)
			(layer "B.Fab")
		)
		(fp_line
			(start 0.12065 0.3048)
			(end 0.67945 0.3048)
			(stroke
				(width 0.1)
				(type default)
			)
			(layer "B.Fab")
		)
		(fp_line
			(start 0.12065 0.2794)
			(end 0.12065 0.3048)
			(stroke
				(width 0.1)
				(type default)
			)
			(layer "B.Fab")
		)
		(fp_line
			(start 0.12065 -0.2794)
			(end -0.12065 -0.2794)
			(stroke
				(width 0.1)
				(type default)
			)
			(layer "B.Fab")
		)
		(fp_line
			(start 0.12065 -0.305054)
			(end 0.12065 -0.2794)
			(stroke
				(width 0.1)
				(type default)
			)
			(layer "B.Fab")
		)
		(fp_line
			(start -0.120396 0.3048)
			(end -0.120396 0.2794)
			(stroke
				(width 0.1)
				(type default)
			)
			(layer "B.Fab")
		)
		(fp_line
			(start -0.120396 0.2794)
			(end 0.12065 0.2794)
			(stroke
				(width 0.1)
				(type default)
			)
			(layer "B.Fab")
		)
		(fp_line
			(start -0.12065 -0.2794)
			(end -0.12065 -0.3048)
			(stroke
				(width 0.1)
				(type default)
			)
			(layer "B.Fab")
		)
		(fp_line
			(start -0.12065 -0.3048)
			(end -0.67945 -0.3048)
			(stroke
				(width 0.1)
				(type default)
			)
			(layer "B.Fab")
		)
		(fp_line
			(start -0.67945 0.3048)
			(end -0.120396 0.3048)
			(stroke
				(width 0.1)
				(type default)
			)
			(layer "B.Fab")
		)
		(fp_line
			(start -0.67945 -0.3048)
			(end -0.67945 0.3048)
			(stroke
				(width 0.1)
				(type default)
			)
			(layer "B.Fab")
		)
		(pad "1" smd circle
			(at 0.40005 0)
			(size 0 0)
			(layers "B.Cu" "B.Mask" "B.Paste")
			(net "PVDDCR_CPU0_P1_TEMP0")
		)
		(pad "2" smd circle
			(at -0.40005 0)
			(size 0 0)
			(layers "B.Cu" "B.Mask" "B.Paste")
			(net "GND")
		)
	)
)
